(kicad_pcb
	(version 20260206)
	(generator "pcbnew")
	(generator_version "10.0")
	(general
		(thickness 1.6)
		(legacy_teardrops no)
	)
	(paper "A4")
	(title_block
		(title "Bryce Canyon_IOM_M2_16342-2_OCP.brd")
		(comment 1 "Bryce Canyon / footprints 690-695 of 1146")
	)
	(layers
		(0 "F.Cu" signal "TOP")
		(4 "In1.Cu" signal "L2GND")
		(6 "In2.Cu" signal "L3")
		(8 "In3.Cu" signal "L4VCC")
		(10 "In4.Cu" signal "L5VCC")
		(12 "In5.Cu" signal "L6")
		(14 "In6.Cu" signal "L7GND")
		(2 "B.Cu" signal "BOTTOM")
		(9 "F.Adhes" user "F.Adhesive")
		(11 "B.Adhes" user "B.Adhesive")
		(13 "F.Paste" user "Package Geometry/Pastemask Top")
		(15 "B.Paste" user "Package Geometry/Pastemask Bottom")
		(5 "F.SilkS" user "Ref Des/Silkscreen Top")
		(7 "B.SilkS" user "Ref Des/Silkscreen Bottom")
		(1 "F.Mask" user "Board Geometry/Soldermask Top")
		(3 "B.Mask" user "Board Geometry/Soldermask Bottom")
		(17 "Dwgs.User" user "User.Drawings")
		(19 "Cmts.User" user "User.Comments")
		(21 "Eco1.User" user "User.Eco1")
		(23 "Eco2.User" user "User.Eco2")
		(25 "Edge.Cuts" user "Board Geometry/Outline")
		(27 "Margin" user)
		(31 "F.CrtYd" user "Package Geometry/Place Bound Top")
		(29 "B.CrtYd" user "Package Geometry/Place Bound Bottom")
		(35 "F.Fab" user "Ref Des/Assembly Top")
		(33 "B.Fab" user "Ref Des/Assembly Bottom")
	)
	(footprint ""
		(layer "F.Cu")
		(at 182.642764 -139.977622 -135)
		(property "Reference" "VIA59"
			(at 0 0 225)
			(layer "F.SilkS")
			(hide yes)
			(effects
				(font
					(size 1.27 1.27)
				)
			)
		)
		(property "Value" "85OHM-8L-1D6MM-L16L18-GP"
			(at 4.064105 0.609655 225)
			(unlocked yes)
			(layer "F.Fab")
			(hide yes)
			(effects
				(font
					(size 1.016 1.016)
					(thickness 0.1524)
				)
			)
		)
		(property "Device Type" "VIA-PCIE-4P-368076"
			(at 4.064105 -0.914474 225)
			(unlocked yes)
			(layer "F.Fab")
			(hide yes)
			(effects
				(font
					(size 1.016 1.016)
					(thickness 0.1524)
				)
			)
		)
		(duplicate_pad_numbers_are_jumpers no)
		(fp_poly
			(pts
				(xy -1.841491 -0.381057) (xy 1.841509 -0.381058) (xy 1.841508 0.380942) (xy -1.841491 0.380942)
			)
			(stroke
				(width 0)
				(type default)
			)
			(fill no)
			(layer "F.CrtYd")
		)
		(fp_poly
			(pts
				(xy -1.841491 -0.381057) (xy 1.841509 -0.381058) (xy 1.841508 0.380942) (xy -1.841491 0.380942)
			)
			(stroke
				(width 0)
				(type default)
			)
			(fill no)
			(layer "F.Fab")
		)
		(pad "1" thru_hole circle
			(at -1.460499 0 225)
			(size 0.508 0.508)
			(drill 0.254)
			(layers "*.Cu" "*.Mask")
			(remove_unused_layers no)
			(net "GND")
			(clearance 0.127)
			(thermal_gap 0.127)
		)
		(pad "2" thru_hole circle
			(at -0.4445 0 225)
			(size 0.508 0.508)
			(drill 0.254)
			(layers "*.Cu" "*.Mask")
			(remove_unused_layers no)
			(net "PCIE_IOM_TO_COMP_12_DP")
			(clearance 0.127)
			(thermal_gap 0.127)
		)
		(pad "3" thru_hole circle
			(at 0.4445 0 225)
			(size 0.508 0.508)
			(drill 0.254)
			(layers "*.Cu" "*.Mask")
			(remove_unused_layers no)
			(net "PCIE_IOM_TO_COMP_12_DN")
			(clearance 0.127)
			(thermal_gap 0.127)
		)
		(pad "4" thru_hole circle
			(at 1.460499 0 225)
			(size 0.508 0.508)
			(drill 0.254)
			(layers "*.Cu" "*.Mask")
			(remove_unused_layers no)
			(net "GND")
			(clearance 0.127)
			(thermal_gap 0.127)
		)
	)
	(footprint ""
		(layer "F.Cu")
		(at 27.419046 -152.340056 -90)
		(property "Reference" "R769"
			(at 0 0 270)
			(layer "F.SilkS")
			(hide yes)
			(effects
				(font
					(size 1.27 1.27)
				)
			)
		)
		(property "Value" "0R2J-2-GP"
			(at 0.064008 -3.993896 270)
			(unlocked yes)
			(layer "F.Fab")
			(hide yes)
			(effects
				(font
					(size 1.016 1.016)
					(thickness 0.1524)
				)
			)
		)
		(property "Device Type" "R402H16"
			(at 0.064008 -5.517896 270)
			(unlocked yes)
			(layer "F.Fab")
			(hide yes)
			(effects
				(font
					(size 1.016 1.016)
					(thickness 0.1524)
				)
			)
		)
		(duplicate_pad_numbers_are_jumpers no)
		(fp_line
			(start -0.508 -0.9398)
			(end -0.508 0.9398)
			(stroke
				(width 0.1524)
				(type default)
			)
			(layer "F.SilkS")
		)
		(fp_line
			(start 0.508 -0.9398)
			(end -0.508 -0.9398)
			(stroke
				(width 0.1524)
				(type default)
			)
			(layer "F.SilkS")
		)
		(fp_rect
			(start -0.508 0.9398)
			(end 0.508 -0.9398)
			(stroke
				(width 0)
				(type default)
			)
			(fill no)
			(layer "F.CrtYd")
		)
		(fp_rect
			(start -0.508 0.9398)
			(end 0.508 -0.9398)
			(stroke
				(width 0)
				(type default)
			)
			(fill no)
			(layer "F.Fab")
		)
		(pad "1" smd custom
			(at 0 -0.4445 270)
			(size 0.1397 0.1397)
			(layers "F.Cu" "F.Mask" "F.Paste")
			(net "DEBUG_GPIO_BMC_R_2")
			(options
				(clearance outline)
				(anchor circle)
			)
			(primitives
				(gr_poly
					(pts
						(arc
							(start -0.1778 -0.2794)
							(mid -0.249642 -0.249642)
							(end -0.2794 -0.1778)
						)
						(arc
							(start -0.2794 0.1778)
							(mid -0.249642 0.249642)
							(end -0.1778 0.2794)
						)
						(arc
							(start 0.1778 0.2794)
							(mid 0.249642 0.249642)
							(end 0.2794 0.1778)
						)
						(arc
							(start 0.2794 -0.1778)
							(mid 0.249642 -0.249642)
							(end 0.1778 -0.2794)
						)
					)
					(width 0)
					(fill yes)
				)
			)
		)
		(pad "2" smd custom
			(at 0 0.4445 270)
			(size 0.1397 0.1397)
			(layers "F.Cu" "F.Mask" "F.Paste")
			(net "DEBUG_GPIO_BMC_2")
			(options
				(clearance outline)
				(anchor circle)
			)
			(primitives
				(gr_poly
					(pts
						(arc
							(start -0.1778 -0.2794)
							(mid -0.249642 -0.249642)
							(end -0.2794 -0.1778)
						)
						(arc
							(start -0.2794 0.1778)
							(mid -0.249642 0.249642)
							(end -0.1778 0.2794)
						)
						(arc
							(start 0.1778 0.2794)
							(mid 0.249642 0.249642)
							(end 0.2794 0.1778)
						)
						(arc
							(start 0.2794 -0.1778)
							(mid 0.249642 -0.249642)
							(end 0.1778 -0.2794)
						)
					)
					(width 0)
					(fill yes)
				)
			)
		)
	)
	(footprint ""
		(layer "F.Cu")
		(at 122.231404 -15.128748 90)
		(property "Reference" "R432"
			(at 0 0 90)
			(layer "F.SilkS")
			(hide yes)
			(effects
				(font
					(size 1.27 1.27)
				)
			)
		)
		(property "Value" "100R2D-GP"
			(at 0.064008 -3.993896 90)
			(unlocked yes)
			(layer "F.Fab")
			(hide yes)
			(effects
				(font
					(size 1.016 1.016)
					(thickness 0.1524)
				)
			)
		)
		(property "Device Type" "R402H14"
			(at 0.064008 -5.517896 90)
			(unlocked yes)
			(layer "F.Fab")
			(hide yes)
			(effects
				(font
					(size 1.016 1.016)
					(thickness 0.1524)
				)
			)
		)
		(duplicate_pad_numbers_are_jumpers no)
		(fp_line
			(start 0.508 -0.9398)
			(end -0.508 -0.9398)
			(stroke
				(width 0.1524)
				(type default)
			)
			(layer "F.SilkS")
		)
		(fp_line
			(start -0.508 -0.9398)
			(end -0.508 0.9398)
			(stroke
				(width 0.1524)
				(type default)
			)
			(layer "F.SilkS")
		)
		(fp_rect
			(start -0.508 0.9398)
			(end 0.508 -0.9398)
			(stroke
				(width 0)
				(type default)
			)
			(fill no)
			(layer "F.CrtYd")
		)
		(fp_rect
			(start -0.508 0.9398)
			(end 0.508 -0.9398)
			(stroke
				(width 0)
				(type default)
			)
			(fill no)
			(layer "F.Fab")
		)
		(pad "1" smd custom
			(at 0 -0.4445 90)
			(size 0.1397 0.1397)
			(layers "F.Cu" "F.Mask" "F.Paste")
			(net "MB0_TEMP")
			(options
				(clearance outline)
				(anchor circle)
			)
			(primitives
				(gr_poly
					(pts
						(arc
							(start -0.1778 -0.2794)
							(mid -0.249642 -0.249642)
							(end -0.2794 -0.1778)
						)
						(arc
							(start -0.2794 0.1778)
							(mid -0.249642 0.249642)
							(end -0.1778 0.2794)
						)
						(arc
							(start 0.1778 0.2794)
							(mid 0.249642 0.249642)
							(end 0.2794 0.1778)
						)
						(arc
							(start 0.2794 -0.1778)
							(mid 0.249642 -0.249642)
							(end 0.1778 -0.2794)
						)
					)
					(width 0)
					(fill yes)
				)
			)
		)
		(pad "2" smd custom
			(at 0 0.4445 90)
			(size 0.1397 0.1397)
			(layers "F.Cu" "F.Mask" "F.Paste")
			(net "MB0_TEMP_C")
			(options
				(clearance outline)
				(anchor circle)
			)
			(primitives
				(gr_poly
					(pts
						(arc
							(start -0.1778 -0.2794)
							(mid -0.249642 -0.249642)
							(end -0.2794 -0.1778)
						)
						(arc
							(start -0.2794 0.1778)
							(mid -0.249642 0.249642)
							(end -0.1778 0.2794)
						)
						(arc
							(start 0.1778 0.2794)
							(mid 0.249642 0.249642)
							(end 0.2794 0.1778)
						)
						(arc
							(start 0.2794 -0.1778)
							(mid 0.249642 -0.249642)
							(end 0.1778 -0.2794)
						)
					)
					(width 0)
					(fill yes)
				)
			)
		)
	)
	(footprint ""
		(layer "F.Cu")
		(at 93.577156 -162.51428 90)
		(property "Reference" "C20"
			(at 0 0 90)
			(layer "F.SilkS")
			(hide yes)
			(effects
				(font
					(size 1.27 1.27)
				)
			)
		)
		(property "Value" "SC18P50V2JN-1-GP"
			(at 1.1811 -2.7051 90)
			(unlocked yes)
			(layer "F.Fab")
			(hide yes)
			(effects
				(font
					(size 1.016 1.016)
					(thickness 0.1524)
				)
			)
		)
		(property "Device Type" "C402H22"
			(at 1.1811 -4.2291 90)
			(unlocked yes)
			(layer "F.Fab")
			(hide yes)
			(effects
				(font
					(size 1.016 1.016)
					(thickness 0.1524)
				)
			)
		)
		(duplicate_pad_numbers_are_jumpers no)
		(fp_rect
			(start -0.4318 0.9525)
			(end 0.4318 -0.9525)
			(stroke
				(width 0)
				(type default)
			)
			(fill no)
			(layer "F.CrtYd")
		)
		(fp_rect
			(start -0.4318 0.9525)
			(end 0.4318 -0.9525)
			(stroke
				(width 0)
				(type default)
			)
			(fill no)
			(layer "F.Fab")
		)
		(pad "1" smd custom
			(at 0 -0.4445 90)
			(size 0.1524 0.1524)
			(layers "F.Cu" "F.Mask" "F.Paste")
			(net "USB_HUB_XTAL_OUT")
			(options
				(clearance outline)
				(anchor circle)
			)
			(primitives
				(gr_poly
					(pts
						(arc
							(start 0.3048 -0.2032)
							(mid 0.275042 -0.275042)
							(end 0.2032 -0.3048)
						)
						(arc
							(start -0.2032 -0.3048)
							(mid -0.275042 -0.275042)
							(end -0.3048 -0.2032)
						)
						(arc
							(start -0.3048 0.2032)
							(mid -0.275042 0.275042)
							(end -0.2032 0.3048)
						)
						(arc
							(start 0.2032 0.3048)
							(mid 0.275042 0.275042)
							(end 0.3048 0.2032)
						)
					)
					(width 0)
					(fill yes)
				)
			)
		)
		(pad "2" smd custom
			(at 0 0.4445 90)
			(size 0.1524 0.1524)
			(layers "F.Cu" "F.Mask" "F.Paste")
			(net "GND")
			(options
				(clearance outline)
				(anchor circle)
			)
			(primitives
				(gr_poly
					(pts
						(arc
							(start 0.3048 -0.2032)
							(mid 0.275042 -0.275042)
							(end 0.2032 -0.3048)
						)
						(arc
							(start -0.2032 -0.3048)
							(mid -0.275042 -0.275042)
							(end -0.3048 -0.2032)
						)
						(arc
							(start -0.3048 0.2032)
							(mid -0.275042 0.275042)
							(end -0.2032 0.3048)
						)
						(arc
							(start 0.2032 0.3048)
							(mid 0.275042 0.275042)
							(end 0.3048 0.2032)
						)
					)
					(width 0)
					(fill yes)
				)
			)
		)
	)
	(footprint ""
		(layer "F.Cu")
		(at 215.60028 -93.109288 90)
		(property "Reference" "C670"
			(at 0 0 90)
			(layer "F.SilkS")
			(hide yes)
			(effects
				(font
					(size 1.27 1.27)
				)
			)
		)
		(property "Value" "SC1U16V3KX-5GP"
			(at 0 -2.8194 90)
			(unlocked yes)
			(layer "F.Fab")
			(hide yes)
			(effects
				(font
					(size 1.016 1.016)
					(thickness 0.1524)
				)
			)
		)
		(property "Device Type" "C603H36"
			(at 0 -4.3434 90)
			(unlocked yes)
			(layer "F.Fab")
			(hide yes)
			(effects
				(font
					(size 1.016 1.016)
					(thickness 0.1524)
				)
			)
		)
		(duplicate_pad_numbers_are_jumpers no)
		(fp_line
			(start 0.508 0)
			(end -0.508 0)
			(stroke
				(width 0.2032)
				(type default)
			)
			(layer "F.SilkS")
		)
		(fp_rect
			(start -0.5842 1.3335)
			(end 0.5842 -1.3335)
			(stroke
				(width 0)
				(type default)
			)
			(fill no)
			(layer "F.CrtYd")
		)
		(fp_rect
			(start -0.5842 1.3335)
			(end 0.5842 -1.3335)
			(stroke
				(width 0)
				(type default)
			)
			(fill no)
			(layer "F.Fab")
		)
		(pad "1" smd custom
			(at 0 -0.762 90)
			(size 0.2159 0.2159)
			(layers "F.Cu" "F.Mask" "F.Paste")
			(net "GND")
			(options
				(clearance outline)
				(anchor circle)
			)
			(primitives
				(gr_poly
					(pts
						(arc
							(start -0.3302 -0.4318)
							(mid -0.402042 -0.402042)
							(end -0.4318 -0.3302)
						)
						(arc
							(start -0.4318 0.3302)
							(mid -0.402042 0.402042)
							(end -0.3302 0.4318)
						)
						(arc
							(start 0.3302 0.4318)
							(mid 0.402042 0.402042)
							(end 0.4318 0.3302)
						)
						(arc
							(start 0.4318 -0.3302)
							(mid 0.402042 -0.402042)
							(end 0.3302 -0.4318)
						)
					)
					(width 0)
					(fill yes)
				)
			)
		)
		(pad "2" smd custom
			(at 0 0.762 90)
			(size 0.2159 0.2159)
			(layers "F.Cu" "F.Mask" "F.Paste")
			(net "P3V3_M2_EN")
			(options
				(clearance outline)
				(anchor circle)
			)
			(primitives
				(gr_poly
					(pts
						(arc
							(start -0.3302 -0.4318)
							(mid -0.402042 -0.402042)
							(end -0.4318 -0.3302)
						)
						(arc
							(start -0.4318 0.3302)
							(mid -0.402042 0.402042)
							(end -0.3302 0.4318)
						)
						(arc
							(start 0.3302 0.4318)
							(mid 0.402042 0.402042)
							(end 0.4318 0.3302)
						)
						(arc
							(start 0.4318 -0.3302)
							(mid 0.402042 -0.402042)
							(end 0.3302 -0.4318)
						)
					)
					(width 0)
					(fill yes)
				)
			)
		)
	)
	(footprint ""
		(layer "F.Cu")
		(at 86.995 -148.717 90)
		(property "Reference" "R93"
			(at 0 0 90)
			(layer "F.SilkS")
			(hide yes)
			(effects
				(font
					(size 1.27 1.27)
				)
			)
		)
		(property "Value" "0R2J-2-GP"
			(at 0.064008 -3.993896 90)
			(unlocked yes)
			(layer "F.Fab")
			(hide yes)
			(effects
				(font
					(size 1.016 1.016)
					(thickness 0.1524)
				)
			)
		)
		(property "Device Type" "R402H16"
			(at 0.064008 -5.517896 90)
			(unlocked yes)
			(layer "F.Fab")
			(hide yes)
			(effects
				(font
					(size 1.016 1.016)
					(thickness 0.1524)
				)
			)
		)
		(duplicate_pad_numbers_are_jumpers no)
		(fp_line
			(start 0.508 -0.9398)
			(end -0.508 -0.9398)
			(stroke
				(width 0.1524)
				(type default)
			)
			(layer "F.SilkS")
		)
		(fp_line
			(start -0.508 -0.9398)
			(end -0.508 0.9398)
			(stroke
				(width 0.1524)
				(type default)
			)
			(layer "F.SilkS")
		)
		(fp_rect
			(start -0.508 0.9398)
			(end 0.508 -0.9398)
			(stroke
				(width 0)
				(type default)
			)
			(fill no)
			(layer "F.CrtYd")
		)
		(fp_rect
			(start -0.508 0.9398)
			(end 0.508 -0.9398)
			(stroke
				(width 0)
				(type default)
			)
			(fill no)
			(layer "F.Fab")
		)
		(pad "1" smd custom
			(at 0 -0.4445 90)
			(size 0.1397 0.1397)
			(layers "F.Cu" "F.Mask" "F.Paste")
			(net "I2C_BMC_COMP_SCL_OUT")
			(options
				(clearance outline)
				(anchor circle)
			)
			(primitives
				(gr_poly
					(pts
						(arc
							(start -0.1778 -0.2794)
							(mid -0.249642 -0.249642)
							(end -0.2794 -0.1778)
						)
						(arc
							(start -0.2794 0.1778)
							(mid -0.249642 0.249642)
							(end -0.1778 0.2794)
						)
						(arc
							(start 0.1778 0.2794)
							(mid 0.249642 0.249642)
							(end 0.2794 0.1778)
						)
						(arc
							(start 0.2794 -0.1778)
							(mid 0.249642 -0.249642)
							(end 0.1778 -0.2794)
						)
					)
					(width 0)
					(fill yes)
				)
			)
		)
		(pad "2" smd custom
			(at 0 0.4445 90)
			(size 0.1397 0.1397)
			(layers "F.Cu" "F.Mask" "F.Paste")
			(net "I2C_BMC_COMP_SCL_R")
			(options
				(clearance outline)
				(anchor circle)
			)
			(primitives
				(gr_poly
					(pts
						(arc
							(start -0.1778 -0.2794)
							(mid -0.249642 -0.249642)
							(end -0.2794 -0.1778)
						)
						(arc
							(start -0.2794 0.1778)
							(mid -0.249642 0.249642)
							(end -0.1778 0.2794)
						)
						(arc
							(start 0.1778 0.2794)
							(mid 0.249642 0.249642)
							(end 0.2794 0.1778)
						)
						(arc
							(start 0.2794 -0.1778)
							(mid 0.249642 -0.249642)
							(end 0.1778 -0.2794)
						)
					)
					(width 0)
					(fill yes)
				)
			)
		)
	)
)
